(kicad_pcb
	(version 20260206)
	(generator "pcbnew")
	(generator_version "10.0")
	(general
		(thickness 1.6)
		(legacy_teardrops no)
	)
	(paper "A4")
	(title_block
		(title "Bryce Canyon_F.DPB_16315-1-OCP.brd")
		(comment 1 "Bryce Canyon / footprints 985-992 of 2223")
	)
	(layers
		(0 "F.Cu" signal "TOP")
		(4 "In1.Cu" signal "L2GND")
		(6 "In2.Cu" signal "L3")
		(8 "In3.Cu" signal "L4GND")
		(10 "In4.Cu" signal "L5")
		(12 "In5.Cu" signal "L6VCC")
		(14 "In6.Cu" signal "L7VCC")
		(16 "In7.Cu" signal "L8")
		(18 "In8.Cu" signal "L9GND")
		(20 "In9.Cu" signal "L10")
		(22 "In10.Cu" signal "L11GND")
		(2 "B.Cu" signal "BOTTOM")
		(9 "F.Adhes" user "F.Adhesive")
		(11 "B.Adhes" user "B.Adhesive")
		(13 "F.Paste" user "Package Geometry/Pastemask Top")
		(15 "B.Paste" user "Package Geometry/Pastemask Bottom")
		(5 "F.SilkS" user "Ref Des/Silkscreen Top")
		(7 "B.SilkS" user "Ref Des/Silkscreen Bottom")
		(1 "F.Mask" user "Board Geometry/Soldermask Top")
		(3 "B.Mask" user "Board Geometry/Soldermask Bottom")
		(17 "Dwgs.User" user "User.Drawings")
		(19 "Cmts.User" user "User.Comments")
		(21 "Eco1.User" user "User.Eco1")
		(23 "Eco2.User" user "User.Eco2")
		(25 "Edge.Cuts" user "Board Geometry/Outline")
		(27 "Margin" user)
		(31 "F.CrtYd" user "Package Geometry/Place Bound Top")
		(29 "B.CrtYd" user "Package Geometry/Place Bound Bottom")
		(35 "F.Fab" user "Ref Des/Assembly Top")
		(33 "B.Fab" user "Ref Des/Assembly Bottom")
	)
	(footprint ""
		(layer "F.Cu")
		(at 427.390052 -164.596318 90)
		(property "Reference" "C321"
			(at 0 0 90)
			(layer "F.SilkS")
			(hide yes)
			(effects
				(font
					(size 1.27 1.27)
				)
			)
		)
		(property "Value" "SCD033U25V2KX-GP"
			(at 1.1811 -2.7051 90)
			(unlocked yes)
			(layer "F.Fab")
			(hide yes)
			(effects
				(font
					(size 1.016 1.016)
					(thickness 0.1524)
				)
			)
		)
		(property "Device Type" "C402H22"
			(at 1.1811 -4.2291 90)
			(unlocked yes)
			(layer "F.Fab")
			(hide yes)
			(effects
				(font
					(size 1.016 1.016)
					(thickness 0.1524)
				)
			)
		)
		(duplicate_pad_numbers_are_jumpers no)
		(fp_rect
			(start -0.4318 0.9525)
			(end 0.4318 -0.9525)
			(stroke
				(width 0)
				(type default)
			)
			(fill no)
			(layer "F.CrtYd")
		)
		(fp_rect
			(start -0.4318 0.9525)
			(end 0.4318 -0.9525)
			(stroke
				(width 0)
				(type default)
			)
			(fill no)
			(layer "F.Fab")
		)
		(pad "1" smd custom
			(at 0 -0.4445 90)
			(size 0.1524 0.1524)
			(layers "F.Cu" "F.Mask" "F.Paste")
			(net "SW_HDD_P21")
			(options
				(clearance outline)
				(anchor circle)
			)
			(primitives
				(gr_poly
					(pts
						(arc
							(start 0.3048 -0.2032)
							(mid 0.275042 -0.275042)
							(end 0.2032 -0.3048)
						)
						(arc
							(start -0.2032 -0.3048)
							(mid -0.275042 -0.275042)
							(end -0.3048 -0.2032)
						)
						(arc
							(start -0.3048 0.2032)
							(mid -0.275042 0.275042)
							(end -0.2032 0.3048)
						)
						(arc
							(start 0.2032 0.3048)
							(mid 0.275042 0.275042)
							(end 0.3048 0.2032)
						)
					)
					(width 0)
					(fill yes)
				)
			)
		)
		(pad "2" smd custom
			(at 0 0.4445 90)
			(size 0.1524 0.1524)
			(layers "F.Cu" "F.Mask" "F.Paste")
			(net "GND")
			(options
				(clearance outline)
				(anchor circle)
			)
			(primitives
				(gr_poly
					(pts
						(arc
							(start 0.3048 -0.2032)
							(mid 0.275042 -0.275042)
							(end 0.2032 -0.3048)
						)
						(arc
							(start -0.2032 -0.3048)
							(mid -0.275042 -0.275042)
							(end -0.3048 -0.2032)
						)
						(arc
							(start -0.3048 0.2032)
							(mid -0.275042 0.275042)
							(end -0.2032 0.3048)
						)
						(arc
							(start 0.2032 0.3048)
							(mid 0.275042 0.275042)
							(end 0.3048 0.2032)
						)
					)
					(width 0)
					(fill yes)
				)
			)
		)
	)
	(footprint ""
		(layer "F.Cu")
		(at 55.790846 -189.462918 180)
		(property "Reference" "C216"
			(at 0 0 180)
			(layer "F.SilkS")
			(hide yes)
			(effects
				(font
					(size 1.27 1.27)
				)
			)
		)
		(property "Value" "SC1U25V3KX-GP"
			(at 0 -2.8194 180)
			(unlocked yes)
			(layer "F.Fab")
			(hide yes)
			(effects
				(font
					(size 1.016 1.016)
					(thickness 0.1524)
				)
			)
		)
		(property "Device Type" "C603H36"
			(at 0 -4.3434 180)
			(unlocked yes)
			(layer "F.Fab")
			(hide yes)
			(effects
				(font
					(size 1.016 1.016)
					(thickness 0.1524)
				)
			)
		)
		(duplicate_pad_numbers_are_jumpers no)
		(fp_line
			(start 0.508 0)
			(end -0.508 0)
			(stroke
				(width 0.2032)
				(type default)
			)
			(layer "F.SilkS")
		)
		(fp_rect
			(start -0.5842 1.3335)
			(end 0.5842 -1.3335)
			(stroke
				(width 0)
				(type default)
			)
			(fill no)
			(layer "F.CrtYd")
		)
		(fp_rect
			(start -0.5842 1.3335)
			(end 0.5842 -1.3335)
			(stroke
				(width 0)
				(type default)
			)
			(fill no)
			(layer "F.Fab")
		)
		(pad "1" smd custom
			(at 0 -0.762 180)
			(size 0.2159 0.2159)
			(layers "F.Cu" "F.Mask" "F.Paste")
			(net "P12V_HDD13")
			(options
				(clearance outline)
				(anchor circle)
			)
			(primitives
				(gr_poly
					(pts
						(arc
							(start -0.3302 -0.4318)
							(mid -0.402042 -0.402042)
							(end -0.4318 -0.3302)
						)
						(arc
							(start -0.4318 0.3302)
							(mid -0.402042 0.402042)
							(end -0.3302 0.4318)
						)
						(arc
							(start 0.3302 0.4318)
							(mid 0.402042 0.402042)
							(end 0.4318 0.3302)
						)
						(arc
							(start 0.4318 -0.3302)
							(mid 0.402042 -0.402042)
							(end 0.3302 -0.4318)
						)
					)
					(width 0)
					(fill yes)
				)
			)
		)
		(pad "2" smd custom
			(at 0 0.762 180)
			(size 0.2159 0.2159)
			(layers "F.Cu" "F.Mask" "F.Paste")
			(net "GND")
			(options
				(clearance outline)
				(anchor circle)
			)
			(primitives
				(gr_poly
					(pts
						(arc
							(start -0.3302 -0.4318)
							(mid -0.402042 -0.402042)
							(end -0.4318 -0.3302)
						)
						(arc
							(start -0.4318 0.3302)
							(mid -0.402042 0.402042)
							(end -0.3302 0.4318)
						)
						(arc
							(start 0.3302 0.4318)
							(mid 0.402042 0.402042)
							(end 0.4318 0.3302)
						)
						(arc
							(start 0.4318 -0.3302)
							(mid 0.402042 -0.402042)
							(end 0.3302 -0.4318)
						)
					)
					(width 0)
					(fill yes)
				)
			)
		)
	)
	(footprint ""
		(layer "F.Cu")
		(at 16.874998 -161.649918 180)
		(property "Reference" "D12"
			(at 0 0 180)
			(layer "F.SilkS")
			(hide yes)
			(effects
				(font
					(size 1.27 1.27)
				)
			)
		)
		(property "Value" "RB551V30-GP"
			(at 0 -6.7818 180)
			(unlocked yes)
			(layer "F.Fab")
			(hide yes)
			(effects
				(font
					(size 1.016 1.016)
					(thickness 0.1524)
				)
			)
		)
		(property "Device Type" "SOD323AKH38"
			(at 0 -8.6868 180)
			(unlocked yes)
			(layer "F.Fab")
			(hide yes)
			(effects
				(font
					(size 1.016 1.016)
					(thickness 0.1524)
				)
			)
		)
		(duplicate_pad_numbers_are_jumpers no)
		(fp_line
			(start 0.889 2.159)
			(end -0.889 2.159)
			(stroke
				(width 0.1524)
				(type default)
			)
			(layer "F.SilkS")
		)
		(fp_line
			(start 0.889 -1.9304)
			(end 0.889 2.159)
			(stroke
				(width 0.1524)
				(type default)
			)
			(layer "F.SilkS")
		)
		(fp_line
			(start 0.762 2.0574)
			(end -0.762 2.0574)
			(stroke
				(width 0.508)
				(type default)
			)
			(layer "F.SilkS")
		)
		(fp_line
			(start -0.889 2.159)
			(end -0.889 -1.9304)
			(stroke
				(width 0.1524)
				(type default)
			)
			(layer "F.SilkS")
		)
		(fp_line
			(start -0.889 -1.9304)
			(end 0.889 -1.9304)
			(stroke
				(width 0.1524)
				(type default)
			)
			(layer "F.SilkS")
		)
		(fp_rect
			(start -1.016 2.3114)
			(end 1.016 -2.0066)
			(stroke
				(width 0)
				(type default)
			)
			(fill no)
			(layer "F.CrtYd")
		)
		(fp_poly
			(pts
				(xy -1.016 -2.0066) (xy 1.016 -2.0066) (xy 1.016 2.3114) (xy -1.016 2.3114)
			)
			(stroke
				(width 0)
				(type default)
			)
			(fill no)
			(layer "F.Fab")
		)
		(pad "A" smd rect
			(at 0 -1.143 180)
			(size 0.5588 1.016)
			(layers "F.Cu" "F.Mask" "F.Paste")
			(net "SW_HDD_R12")
		)
		(pad "K" smd rect
			(at 0 1.143 180)
			(size 0.5588 1.016)
			(layers "F.Cu" "F.Mask" "F.Paste")
			(net "SW_HDD_N12")
		)
	)
	(footprint ""
		(layer "F.Cu")
		(at 55.486046 -71.287894)
		(property "Reference" "C369"
			(at 0 0 0)
			(layer "F.SilkS")
			(hide yes)
			(effects
				(font
					(size 1.27 1.27)
				)
			)
		)
		(property "Value" "SC4D7U25V5KX-1-GP"
			(at -0.0762 -6.1214 0)
			(unlocked yes)
			(layer "F.Fab")
			(hide yes)
			(effects
				(font
					(size 1.016 1.016)
					(thickness 0.1524)
				)
			)
		)
		(property "Device Type" "C805H58"
			(at -0.0762 -8.1534 0)
			(unlocked yes)
			(layer "F.Fab")
			(hide yes)
			(effects
				(font
					(size 1.016 1.016)
					(thickness 0.1524)
				)
			)
		)
		(duplicate_pad_numbers_are_jumpers no)
		(fp_line
			(start 0.635 0)
			(end -0.635 0)
			(stroke
				(width 0.508)
				(type default)
			)
			(layer "F.SilkS")
		)
		(fp_rect
			(start -0.9652 1.778)
			(end 0.9652 -1.778)
			(stroke
				(width 0)
				(type default)
			)
			(fill no)
			(layer "F.CrtYd")
		)
		(fp_poly
			(pts
				(xy -0.9652 -1.778) (xy 0.9652 -1.778) (xy 0.9652 1.778) (xy -0.9652 1.778)
			)
			(stroke
				(width 0)
				(type default)
			)
			(fill no)
			(layer "F.Fab")
		)
		(pad "1" smd rect
			(at 0 -0.9652)
			(size 1.397 1.143)
			(layers "F.Cu" "F.Mask" "F.Paste")
			(net "P12V_HDD25")
		)
		(pad "2" smd rect
			(at 0 0.9652)
			(size 1.397 1.143)
			(layers "F.Cu" "F.Mask" "F.Paste")
			(net "GND")
		)
	)
	(footprint ""
		(layer "F.Cu")
		(at 331.47 -188.954918 180)
		(property "Reference" "C278"
			(at 0 0 180)
			(layer "F.SilkS")
			(hide yes)
			(effects
				(font
					(size 1.27 1.27)
				)
			)
		)
		(property "Value" "SC4D7U25V5KX-1-GP"
			(at -0.0762 -6.1214 180)
			(unlocked yes)
			(layer "F.Fab")
			(hide yes)
			(effects
				(font
					(size 1.016 1.016)
					(thickness 0.1524)
				)
			)
		)
		(property "Device Type" "C805H58"
			(at -0.0762 -8.1534 180)
			(unlocked yes)
			(layer "F.Fab")
			(hide yes)
			(effects
				(font
					(size 1.016 1.016)
					(thickness 0.1524)
				)
			)
		)
		(duplicate_pad_numbers_are_jumpers no)
		(fp_line
			(start 0.635 0)
			(end -0.635 0)
			(stroke
				(width 0.508)
				(type default)
			)
			(layer "F.SilkS")
		)
		(fp_rect
			(start -0.9652 1.778)
			(end 0.9652 -1.778)
			(stroke
				(width 0)
				(type default)
			)
			(fill no)
			(layer "F.CrtYd")
		)
		(fp_poly
			(pts
				(xy -0.9652 -1.778) (xy 0.9652 -1.778) (xy 0.9652 1.778) (xy -0.9652 1.778)
			)
			(stroke
				(width 0)
				(type default)
			)
			(fill no)
			(layer "F.Fab")
		)
		(pad "1" smd rect
			(at 0 -0.9652 180)
			(size 1.397 1.143)
			(layers "F.Cu" "F.Mask" "F.Paste")
			(net "P12V_HDD18")
		)
		(pad "2" smd rect
			(at 0 0.9652 180)
			(size 1.397 1.143)
			(layers "F.Cu" "F.Mask" "F.Paste")
			(net "GND")
		)
	)
	(footprint ""
		(layer "F.Cu")
		(at 374.588532 -245.303802 -90)
		(property "Reference" "R486"
			(at 0 0 270)
			(layer "F.SilkS")
			(hide yes)
			(effects
				(font
					(size 1.27 1.27)
				)
			)
		)
		(property "Value" "4K7R2J-2-GP"
			(at 0.064008 -3.993896 270)
			(unlocked yes)
			(layer "F.Fab")
			(hide yes)
			(effects
				(font
					(size 1.016 1.016)
					(thickness 0.1524)
				)
			)
		)
		(property "Device Type" "R402H16"
			(at 0.064008 -5.517896 270)
			(unlocked yes)
			(layer "F.Fab")
			(hide yes)
			(effects
				(font
					(size 1.016 1.016)
					(thickness 0.1524)
				)
			)
		)
		(duplicate_pad_numbers_are_jumpers no)
		(fp_line
			(start -0.508 -0.9398)
			(end -0.508 0.9398)
			(stroke
				(width 0.1524)
				(type default)
			)
			(layer "F.SilkS")
		)
		(fp_line
			(start 0.508 -0.9398)
			(end -0.508 -0.9398)
			(stroke
				(width 0.1524)
				(type default)
			)
			(layer "F.SilkS")
		)
		(fp_rect
			(start -0.508 0.9398)
			(end 0.508 -0.9398)
			(stroke
				(width 0)
				(type default)
			)
			(fill no)
			(layer "F.CrtYd")
		)
		(fp_rect
			(start -0.508 0.9398)
			(end 0.508 -0.9398)
			(stroke
				(width 0)
				(type default)
			)
			(fill no)
			(layer "F.Fab")
		)
		(pad "1" smd custom
			(at 0 -0.4445 270)
			(size 0.1397 0.1397)
			(layers "F.Cu" "F.Mask" "F.Paste")
			(net "DRIVE_A_8_FLT_LED")
			(options
				(clearance outline)
				(anchor circle)
			)
			(primitives
				(gr_poly
					(pts
						(arc
							(start -0.1778 -0.2794)
							(mid -0.249642 -0.249642)
							(end -0.2794 -0.1778)
						)
						(arc
							(start -0.2794 0.1778)
							(mid -0.249642 0.249642)
							(end -0.1778 0.2794)
						)
						(arc
							(start 0.1778 0.2794)
							(mid 0.249642 0.249642)
							(end 0.2794 0.1778)
						)
						(arc
							(start 0.2794 -0.1778)
							(mid 0.249642 -0.249642)
							(end 0.1778 -0.2794)
						)
					)
					(width 0)
					(fill yes)
				)
			)
		)
		(pad "2" smd custom
			(at 0 0.4445 270)
			(size 0.1397 0.1397)
			(layers "F.Cu" "F.Mask" "F.Paste")
			(net "GND")
			(options
				(clearance outline)
				(anchor circle)
			)
			(primitives
				(gr_poly
					(pts
						(arc
							(start -0.1778 -0.2794)
							(mid -0.249642 -0.249642)
							(end -0.2794 -0.1778)
						)
						(arc
							(start -0.2794 0.1778)
							(mid -0.249642 0.249642)
							(end -0.1778 0.2794)
						)
						(arc
							(start 0.1778 0.2794)
							(mid 0.249642 0.249642)
							(end 0.2794 0.1778)
						)
						(arc
							(start 0.2794 -0.1778)
							(mid 0.249642 -0.249642)
							(end 0.1778 -0.2794)
						)
					)
					(width 0)
					(fill yes)
				)
			)
		)
	)
	(footprint ""
		(layer "F.Cu")
		(at 118.382796 -62.270894)
		(property "Reference" "R750"
			(at 0 0 0)
			(layer "F.SilkS")
			(hide yes)
			(effects
				(font
					(size 1.27 1.27)
				)
			)
		)
		(property "Value" "2R6F-GP"
			(at -0.0508 -4.8514 0)
			(unlocked yes)
			(layer "F.Fab")
			(hide yes)
			(effects
				(font
					(size 1.016 1.016)
					(thickness 0.1524)
				)
			)
		)
		(property "Device Type" "R1206H26"
			(at 0 -6.3754 0)
			(unlocked yes)
			(layer "F.Fab")
			(hide yes)
			(effects
				(font
					(size 1.016 1.016)
					(thickness 0.1524)
				)
			)
		)
		(duplicate_pad_numbers_are_jumpers no)
		(fp_line
			(start -1.016 -2.2352)
			(end 1.016 -2.2352)
			(stroke
				(width 0.1524)
				(type default)
			)
			(layer "F.SilkS")
		)
		(fp_line
			(start -1.016 2.2352)
			(end -1.016 -2.2352)
			(stroke
				(width 0.1524)
				(type default)
			)
			(layer "F.SilkS")
		)
		(fp_line
			(start 1.016 -2.2352)
			(end 1.016 2.2352)
			(stroke
				(width 0.1524)
				(type default)
			)
			(layer "F.SilkS")
		)
		(fp_line
			(start 1.016 2.2352)
			(end -1.016 2.2352)
			(stroke
				(width 0.1524)
				(type default)
			)
			(layer "F.SilkS")
		)
		(fp_rect
			(start -1.0922 2.3114)
			(end 1.0922 -2.3114)
			(stroke
				(width 0)
				(type default)
			)
			(fill no)
			(layer "F.CrtYd")
		)
		(fp_poly
			(pts
				(xy -1.0922 -2.3114) (xy 1.0922 -2.3114) (xy 1.0922 2.3114) (xy -1.0922 2.3114)
			)
			(stroke
				(width 0)
				(type default)
			)
			(fill no)
			(layer "F.Fab")
		)
		(pad "1" smd rect
			(at 0 -1.397)
			(size 1.651 1.27)
			(layers "F.Cu" "F.Mask" "F.Paste")
			(net "P5V_HDD27")
		)
		(pad "2" smd rect
			(at 0 1.397)
			(size 1.651 1.27)
			(layers "F.Cu" "F.Mask" "F.Paste")
			(net "5V_PRE_27")
		)
	)
	(footprint ""
		(layer "F.Cu")
		(at 475.149926 -61.000894 -90)
		(property "Reference" "C496"
			(at 0 0 270)
			(layer "F.SilkS")
			(hide yes)
			(effects
				(font
					(size 1.27 1.27)
				)
			)
		)
		(property "Value" "SC10U16V6KX-2GP"
			(at -0.0762 -5.1308 270)
			(unlocked yes)
			(layer "F.Fab")
			(hide yes)
			(effects
				(font
					(size 1.016 1.016)
					(thickness 0.1524)
				)
			)
		)
		(property "Device Type" "C1206H71"
			(at -0.127 -6.6548 270)
			(unlocked yes)
			(layer "F.Fab")
			(hide yes)
			(effects
				(font
					(size 1.016 1.016)
					(thickness 0.1524)
				)
			)
		)
		(duplicate_pad_numbers_are_jumpers no)
		(fp_line
			(start -1.016 2.2352)
			(end -1.016 0.8382)
			(stroke
				(width 0.1524)
				(type default)
			)
			(layer "F.SilkS")
		)
		(fp_line
			(start 1.016 2.2352)
			(end -1.016 2.2352)
			(stroke
				(width 0.1524)
				(type default)
			)
			(layer "F.SilkS")
		)
		(fp_line
			(start 1.016 0.8382)
			(end 1.016 2.2352)
			(stroke
				(width 0.1524)
				(type default)
			)
			(layer "F.SilkS")
		)
		(fp_line
			(start -1.016 -0.8382)
			(end -1.016 -2.2352)
			(stroke
				(width 0.1524)
				(type default)
			)
			(layer "F.SilkS")
		)
		(fp_line
			(start -1.016 -2.2352)
			(end 1.016 -2.2352)
			(stroke
				(width 0.1524)
				(type default)
			)
			(layer "F.SilkS")
		)
		(fp_line
			(start 1.016 -2.2352)
			(end 1.016 -0.8382)
			(stroke
				(width 0.1524)
				(type default)
			)
			(layer "F.SilkS")
		)
		(fp_rect
			(start -1.0922 2.3114)
			(end 1.0922 -2.3114)
			(stroke
				(width 0)
				(type default)
			)
			(fill no)
			(layer "F.CrtYd")
		)
		(fp_poly
			(pts
				(xy 1.0922 -2.3114) (xy 1.0922 2.3114) (xy -1.0922 2.3114) (xy -1.0922 -2.3114)
			)
			(stroke
				(width 0)
				(type default)
			)
			(fill no)
			(layer "F.Fab")
		)
		(pad "1" smd rect
			(at 0 -1.397 270)
			(size 1.651 1.27)
			(layers "F.Cu" "F.Mask" "F.Paste")
			(net "P5V_HDD35")
		)
		(pad "2" smd rect
			(at 0 1.397 270)
			(size 1.651 1.27)
			(layers "F.Cu" "F.Mask" "F.Paste")
			(net "GND")
		)
	)
)
